G04 ================== begin FILE IDENTIFICATION RECORD ==================*
G04 Layout Name:  D:/<user>/Wistron_project/16342-2/gbr/16342-2.brd*
G04 Film Name:    BSMD*
G04 File Format:  Gerber RS274X*
G04 File Origin:  Cadence Allegro 16.5-S056*
G04 Origin Date:  Mon Aug 07 11:24:12 2017*
G04 *
G04 Layer:  VIA CLASS/PASTEMASK_BOTTOM*
G04 Layer:  PIN/PASTEMASK_BOTTOM*
G04 Layer:  PACKAGE GEOMETRY/PASTEMASK_BOTTOM*
G04 Layer:  DRAWING FORMAT/LAYER_PCB_STORY*
G04 Layer:  DRAWING FORMAT/LAYER_PAST_B*
G04 Layer:  BOARD GEOMETRY/PANEL_OUTLINE*
G04 *
G04 Offset:    (0.00 0.00)*
G04 Mirror:    No*
G04 Mode:      Positive*
G04 Rotation:  0*
G04 FullContactRelief:  No*
G04 UndefLineWidth:     6.00*
G04 ================== end FILE IDENTIFICATION RECORD ====================*
%FSLAX35Y35*MOIN*%
%IR0*IPPOS*OFA0.00000B0.00000*MIA0B0*SFA1.00000B1.00000*%
%AMMACRO36*
4,1,40,.011,.007,
.011,-.007,
.010939,-.007695,
.010759,-.008368,
.010464,-.009,
.010064,-.009571,
.009571,-.010064,
.009,-.010464,
.008368,-.010759,
.007695,-.010939,
.007,-.011,
-.007,-.011,
-.007695,-.010939,
-.008368,-.010759,
-.009,-.010464,
-.009571,-.010064,
-.010064,-.009571,
-.010464,-.009,
-.010759,-.008368,
-.010939,-.007695,
-.011,-.007,
-.011,.007,
-.010939,.007695,
-.010759,.008368,
-.010464,.009,
-.010064,.009571,
-.009571,.010064,
-.009,.010464,
-.008368,.010759,
-.007695,.010939,
-.007,.011,
.007,.011,
.007695,.010939,
.008368,.010759,
.009,.010464,
.009571,.010064,
.010064,.009571,
.010464,.009,
.010759,.008368,
.010939,.007695,
.011,.007,
0.0*
%
%ADD36MACRO36*%
%AMMACRO22*
4,1,40,-.017,-.013,
-.017,.013,
-.016939,.013695,
-.016759,.014368,
-.016464,.015,
-.016064,.015571,
-.015571,.016064,
-.015,.016464,
-.014368,.016759,
-.013695,.016939,
-.013,.017,
.013,.017,
.013695,.016939,
.014368,.016759,
.015,.016464,
.015571,.016064,
.016064,.015571,
.016464,.015,
.016759,.014368,
.016939,.013695,
.017,.013,
.017,-.013,
.016939,-.013695,
.016759,-.014368,
.016464,-.015,
.016064,-.015571,
.015571,-.016064,
.015,-.016464,
.014368,-.016759,
.013695,-.016939,
.013,-.017,
-.013,-.017,
-.013695,-.016939,
-.014368,-.016759,
-.015,-.016464,
-.015571,-.016064,
-.016064,-.015571,
-.016464,-.015,
-.016759,-.014368,
-.016939,-.013695,
-.017,-.013,
0.0*
%
%ADD22MACRO22*%
%AMMACRO20*
4,1,40,.013,-.017,
-.013,-.017,
-.013695,-.016939,
-.014368,-.016759,
-.015,-.016464,
-.015571,-.016064,
-.016064,-.015571,
-.016464,-.015,
-.016759,-.014368,
-.016939,-.013695,
-.017,-.013,
-.017,.013,
-.016939,.013695,
-.016759,.014368,
-.016464,.015,
-.016064,.015571,
-.015571,.016064,
-.015,.016464,
-.014368,.016759,
-.013695,.016939,
-.013,.017,
.013,.017,
.013695,.016939,
.014368,.016759,
.015,.016464,
.015571,.016064,
.016064,.015571,
.016464,.015,
.016759,.014368,
.016939,.013695,
.017,.013,
.017,-.013,
.016939,-.013695,
.016759,-.014368,
.016464,-.015,
.016064,-.015571,
.015571,-.016064,
.015,-.016464,
.014368,-.016759,
.013695,-.016939,
.013,-.017,
0.0*
%
%ADD20MACRO20*%
%AMMACRO52*
4,1,3,.0125,0.0,
-.0125,.025,
-.0125,-.025,
.0125,0.0,
0.0*
%
%ADD52MACRO52*%
%ADD10C,.04*%
%ADD39C,.032*%
%ADD17C,.024*%
%ADD37C,.028*%
%AMMACRO45*
4,1,40,.008,.014,
-.008,.014,
-.008695,.013939,
-.009368,.013759,
-.01,.013464,
-.010571,.013064,
-.011064,.012571,
-.011464,.012,
-.011759,.011368,
-.011939,.010695,
-.012,.01,
-.012,-.01,
-.011939,-.010695,
-.011759,-.011368,
-.011464,-.012,
-.011064,-.012571,
-.010571,-.013064,
-.01,-.013464,
-.009368,-.013759,
-.008695,-.013939,
-.008,-.014,
.008,-.014,
.008695,-.013939,
.009368,-.013759,
.01,-.013464,
.010571,-.013064,
.011064,-.012571,
.011464,-.012,
.011759,-.011368,
.011939,-.010695,
.012,-.01,
.012,.01,
.011939,.010695,
.011759,.011368,
.011464,.012,
.011064,.012571,
.010571,.013064,
.01,.013464,
.009368,.013759,
.008695,.013939,
.008,.014,
0.0*
%
%ADD45MACRO45*%
%AMMACRO50*
4,1,40,.007,-.0225,
.008389,-.022378,
.009736,-.022018,
.011,-.021428,
.012142,-.020628,
.013128,-.019642,
.013928,-.0185,
.014518,-.017236,
.014878,-.015889,
.015,-.0145,
.015,.0145,
.014878,.015889,
.014518,.017236,
.013928,.0185,
.013128,.019642,
.012142,.020628,
.011,.021428,
.009736,.022018,
.008389,.022378,
.007,.0225,
-.007,.0225,
-.008389,.022378,
-.009736,.022018,
-.011,.021428,
-.012142,.020628,
-.013128,.019642,
-.013928,.0185,
-.014518,.017236,
-.014878,.015889,
-.015,.0145,
-.015,-.0145,
-.014878,-.015889,
-.014518,-.017236,
-.013928,-.0185,
-.013128,-.019642,
-.012142,-.020628,
-.011,-.021428,
-.009736,-.022018,
-.008389,-.022378,
-.007,-.0225,
.007,-.0225,
0.0*
%
%ADD50MACRO50*%
%AMMACRO49*
4,1,40,.014,-.008,
.014,.008,
.013939,.008695,
.013759,.009368,
.013464,.01,
.013064,.010571,
.012571,.011064,
.012,.011464,
.011368,.011759,
.010695,.011939,
.01,.012,
-.01,.012,
-.010695,.011939,
-.011368,.011759,
-.012,.011464,
-.012571,.011064,
-.013064,.010571,
-.013464,.01,
-.013759,.009368,
-.013939,.008695,
-.014,.008,
-.014,-.008,
-.013939,-.008695,
-.013759,-.009368,
-.013464,-.01,
-.013064,-.010571,
-.012571,-.011064,
-.012,-.011464,
-.011368,-.011759,
-.010695,-.011939,
-.01,-.012,
.01,-.012,
.010695,-.011939,
.011368,-.011759,
.012,-.011464,
.012571,-.011064,
.013064,-.010571,
.013464,-.01,
.013759,-.009368,
.013939,-.008695,
.014,-.008,
0.0*
%
%ADD49MACRO49*%
%AMMACRO26*
4,1,40,.007,-.011,
-.007,-.011,
-.007695,-.010939,
-.008368,-.010759,
-.009,-.010464,
-.009571,-.010064,
-.010064,-.009571,
-.010464,-.009,
-.010759,-.008368,
-.010939,-.007695,
-.011,-.007,
-.011,.007,
-.010939,.007695,
-.010759,.008368,
-.010464,.009,
-.010064,.009571,
-.009571,.010064,
-.009,.010464,
-.008368,.010759,
-.007695,.010939,
-.007,.011,
.007,.011,
.007695,.010939,
.008368,.010759,
.009,.010464,
.009571,.010064,
.010064,.009571,
.010464,.009,
.010759,.008368,
.010939,.007695,
.011,.007,
.011,-.007,
.010939,-.007695,
.010759,-.008368,
.010464,-.009,
.010064,-.009571,
.009571,-.010064,
.009,-.010464,
.008368,-.010759,
.007695,-.010939,
.007,-.011,
0.0*
%
%ADD26MACRO26*%
%AMMACRO13*
4,1,40,-.011,-.007,
-.011,.007,
-.010939,.007695,
-.010759,.008368,
-.010464,.009,
-.010064,.009571,
-.009571,.010064,
-.009,.010464,
-.008368,.010759,
-.007695,.010939,
-.007,.011,
.007,.011,
.007695,.010939,
.008368,.010759,
.009,.010464,
.009571,.010064,
.010064,.009571,
.010464,.009,
.010759,.008368,
.010939,.007695,
.011,.007,
.011,-.007,
.010939,-.007695,
.010759,-.008368,
.010464,-.009,
.010064,-.009571,
.009571,-.010064,
.009,-.010464,
.008368,-.010759,
.007695,-.010939,
.007,-.011,
-.007,-.011,
-.007695,-.010939,
-.008368,-.010759,
-.009,-.010464,
-.009571,-.010064,
-.010064,-.009571,
-.010464,-.009,
-.010759,-.008368,
-.010939,-.007695,
-.011,-.007,
0.0*
%
%ADD13MACRO13*%
%AMMACRO32*
4,1,40,-.012,-.008,
-.012,.008,
-.011939,.008695,
-.011759,.009368,
-.011464,.01,
-.011064,.010571,
-.010571,.011064,
-.01,.011464,
-.009368,.011759,
-.008695,.011939,
-.008,.012,
.008,.012,
.008695,.011939,
.009368,.011759,
.01,.011464,
.010571,.011064,
.011064,.010571,
.011464,.01,
.011759,.009368,
.011939,.008695,
.012,.008,
.012,-.008,
.011939,-.008695,
.011759,-.009368,
.011464,-.01,
.011064,-.010571,
.010571,-.011064,
.01,-.011464,
.009368,-.011759,
.008695,-.011939,
.008,-.012,
-.008,-.012,
-.008695,-.011939,
-.009368,-.011759,
-.01,-.011464,
-.010571,-.011064,
-.011064,-.010571,
-.011464,-.01,
-.011759,-.009368,
-.011939,-.008695,
-.012,-.008,
0.0*
%
%ADD32MACRO32*%
%AMMACRO34*
4,1,40,-.008,.012,
.008,.012,
.008695,.011939,
.009368,.011759,
.01,.011464,
.010571,.011064,
.011064,.010571,
.011464,.01,
.011759,.009368,
.011939,.008695,
.012,.008,
.012,-.008,
.011939,-.008695,
.011759,-.009368,
.011464,-.01,
.011064,-.010571,
.010571,-.011064,
.01,-.011464,
.009368,-.011759,
.008695,-.011939,
.008,-.012,
-.008,-.012,
-.008695,-.011939,
-.009368,-.011759,
-.01,-.011464,
-.010571,-.011064,
-.011064,-.010571,
-.011464,-.01,
-.011759,-.009368,
-.011939,-.008695,
-.012,-.008,
-.012,.008,
-.011939,.008695,
-.011759,.009368,
-.011464,.01,
-.011064,.010571,
-.010571,.011064,
-.01,.011464,
-.009368,.011759,
-.008695,.011939,
-.008,.012,
0.0*
%
%ADD34MACRO34*%
%AMMACRO29*
4,1,40,-.013,.017,
.013,.017,
.013695,.016939,
.014368,.016759,
.015,.016464,
.015571,.016064,
.016064,.015571,
.016464,.015,
.016759,.014368,
.016939,.013695,
.017,.013,
.017,-.013,
.016939,-.013695,
.016759,-.014368,
.016464,-.015,
.016064,-.015571,
.015571,-.016064,
.015,-.016464,
.014368,-.016759,
.013695,-.016939,
.013,-.017,
-.013,-.017,
-.013695,-.016939,
-.014368,-.016759,
-.015,-.016464,
-.015571,-.016064,
-.016064,-.015571,
-.016464,-.015,
-.016759,-.014368,
-.016939,-.013695,
-.017,-.013,
-.017,.013,
-.016939,.013695,
-.016759,.014368,
-.016464,.015,
-.016064,.015571,
-.015571,.016064,
-.015,.016464,
-.014368,.016759,
-.013695,.016939,
-.013,.017,
0.0*
%
%ADD29MACRO29*%
%AMMACRO40*
4,1,40,.017,.013,
.017,-.013,
.016939,-.013695,
.016759,-.014368,
.016464,-.015,
.016064,-.015571,
.015571,-.016064,
.015,-.016464,
.014368,-.016759,
.013695,-.016939,
.013,-.017,
-.013,-.017,
-.013695,-.016939,
-.014368,-.016759,
-.015,-.016464,
-.015571,-.016064,
-.016064,-.015571,
-.016464,-.015,
-.016759,-.014368,
-.016939,-.013695,
-.017,-.013,
-.017,.013,
-.016939,.013695,
-.016759,.014368,
-.016464,.015,
-.016064,.015571,
-.015571,.016064,
-.015,.016464,
-.014368,.016759,
-.013695,.016939,
-.013,.017,
.013,.017,
.013695,.016939,
.014368,.016759,
.015,.016464,
.015571,.016064,
.016064,.015571,
.016464,.015,
.016759,.014368,
.016939,.013695,
.017,.013,
0.0*
%
%ADD40MACRO40*%
%AMMACRO27*
4,1,40,.007,-.011,
-.007,-.011,
-.007695,-.010939,
-.008368,-.010759,
-.009,-.010464,
-.009571,-.010064,
-.010064,-.009571,
-.010464,-.009,
-.010759,-.008368,
-.010939,-.007695,
-.011,-.007,
-.011,.007,
-.010939,.007695,
-.010759,.008368,
-.010464,.009,
-.010064,.009571,
-.009571,.010064,
-.009,.010464,
-.008368,.010759,
-.007695,.010939,
-.007,.011,
.007,.011,
.007695,.010939,
.008368,.010759,
.009,.010464,
.009571,.010064,
.010064,.009571,
.010464,.009,
.010759,.008368,
.010939,.007695,
.011,.007,
.011,-.007,
.010939,-.007695,
.010759,-.008368,
.010464,-.009,
.010064,-.009571,
.009571,-.010064,
.009,-.010464,
.008368,-.010759,
.007695,-.010939,
.007,-.011,
0.0*
%
%ADD27MACRO27*%
%AMMACRO14*
4,1,40,-.011,-.007,
-.011,.007,
-.010939,.007695,
-.010759,.008368,
-.010464,.009,
-.010064,.009571,
-.009571,.010064,
-.009,.010464,
-.008368,.010759,
-.007695,.010939,
-.007,.011,
.007,.011,
.007695,.010939,
.008368,.010759,
.009,.010464,
.009571,.010064,
.010064,.009571,
.010464,.009,
.010759,.008368,
.010939,.007695,
.011,.007,
.011,-.007,
.010939,-.007695,
.010759,-.008368,
.010464,-.009,
.010064,-.009571,
.009571,-.010064,
.009,-.010464,
.008368,-.010759,
.007695,-.010939,
.007,-.011,
-.007,-.011,
-.007695,-.010939,
-.008368,-.010759,
-.009,-.010464,
-.009571,-.010064,
-.010064,-.009571,
-.010464,-.009,
-.010759,-.008368,
-.010939,-.007695,
-.011,-.007,
0.0*
%
%ADD14MACRO14*%
%AMMACRO31*
4,1,40,-.012,-.008,
-.012,.008,
-.011939,.008695,
-.011759,.009368,
-.011464,.01,
-.011064,.010571,
-.010571,.011064,
-.01,.011464,
-.009368,.011759,
-.008695,.011939,
-.008,.012,
.008,.012,
.008695,.011939,
.009368,.011759,
.01,.011464,
.010571,.011064,
.011064,.010571,
.011464,.01,
.011759,.009368,
.011939,.008695,
.012,.008,
.012,-.008,
.011939,-.008695,
.011759,-.009368,
.011464,-.01,
.011064,-.010571,
.010571,-.011064,
.01,-.011464,
.009368,-.011759,
.008695,-.011939,
.008,-.012,
-.008,-.012,
-.008695,-.011939,
-.009368,-.011759,
-.01,-.011464,
-.010571,-.011064,
-.011064,-.010571,
-.011464,-.01,
-.011759,-.009368,
-.011939,-.008695,
-.012,-.008,
0.0*
%
%ADD31MACRO31*%
%AMMACRO33*
4,1,40,-.008,.012,
.008,.012,
.008695,.011939,
.009368,.011759,
.01,.011464,
.010571,.011064,
.011064,.010571,
.011464,.01,
.011759,.009368,
.011939,.008695,
.012,.008,
.012,-.008,
.011939,-.008695,
.011759,-.009368,
.011464,-.01,
.011064,-.010571,
.010571,-.011064,
.01,-.011464,
.009368,-.011759,
.008695,-.011939,
.008,-.012,
-.008,-.012,
-.008695,-.011939,
-.009368,-.011759,
-.01,-.011464,
-.010571,-.011064,
-.011064,-.010571,
-.011464,-.01,
-.011759,-.009368,
-.011939,-.008695,
-.012,-.008,
-.012,.008,
-.011939,.008695,
-.011759,.009368,
-.011464,.01,
-.011064,.010571,
-.010571,.011064,
-.01,.011464,
-.009368,.011759,
-.008695,.011939,
-.008,.012,
0.0*
%
%ADD33MACRO33*%
%AMMACRO30*
4,1,40,-.013,.017,
.013,.017,
.013695,.016939,
.014368,.016759,
.015,.016464,
.015571,.016064,
.016064,.015571,
.016464,.015,
.016759,.014368,
.016939,.013695,
.017,.013,
.017,-.013,
.016939,-.013695,
.016759,-.014368,
.016464,-.015,
.016064,-.015571,
.015571,-.016064,
.015,-.016464,
.014368,-.016759,
.013695,-.016939,
.013,-.017,
-.013,-.017,
-.013695,-.016939,
-.014368,-.016759,
-.015,-.016464,
-.015571,-.016064,
-.016064,-.015571,
-.016464,-.015,
-.016759,-.014368,
-.016939,-.013695,
-.017,-.013,
-.017,.013,
-.016939,.013695,
-.016759,.014368,
-.016464,.015,
-.016064,.015571,
-.015571,.016064,
-.015,.016464,
-.014368,.016759,
-.013695,.016939,
-.013,.017,
0.0*
%
%ADD30MACRO30*%
%AMMACRO41*
4,1,40,.017,.013,
.017,-.013,
.016939,-.013695,
.016759,-.014368,
.016464,-.015,
.016064,-.015571,
.015571,-.016064,
.015,-.016464,
.014368,-.016759,
.013695,-.016939,
.013,-.017,
-.013,-.017,
-.013695,-.016939,
-.014368,-.016759,
-.015,-.016464,
-.015571,-.016064,
-.016064,-.015571,
-.016464,-.015,
-.016759,-.014368,
-.016939,-.013695,
-.017,-.013,
-.017,.013,
-.016939,.013695,
-.016759,.014368,
-.016464,.015,
-.016064,.015571,
-.015571,.016064,
-.015,.016464,
-.014368,.016759,
-.013695,.016939,
-.013,.017,
.013,.017,
.013695,.016939,
.014368,.016759,
.015,.016464,
.015571,.016064,
.016064,.015571,
.016464,.015,
.016759,.014368,
.016939,.013695,
.017,.013,
0.0*
%
%ADD41MACRO41*%
%AMMACRO53*
4,1,3,.0125,.025,
-.0125,0.0,
.0125,-.025,
.0125,.025,
0.0*
%
%ADD53MACRO53*%
%ADD38R,.06X.014*%
%ADD51R,.014X.06*%
%ADD46R,.05X.065*%
%ADD28R,.048X.016*%
%ADD18R,.045X.055*%
%ADD43R,.016X.048*%
%ADD25R,.055X.045*%
%AMMACRO48*
4,1,40,-.014,.008,
-.014,-.008,
-.013939,-.008695,
-.013759,-.009368,
-.013464,-.01,
-.013064,-.010571,
-.012571,-.011064,
-.012,-.011464,
-.011368,-.011759,
-.010695,-.011939,
-.01,-.012,
.01,-.012,
.010695,-.011939,
.011368,-.011759,
.012,-.011464,
.012571,-.011064,
.013064,-.010571,
.013464,-.01,
.013759,-.009368,
.013939,-.008695,
.014,-.008,
.014,.008,
.013939,.008695,
.013759,.009368,
.013464,.01,
.013064,.010571,
.012571,.011064,
.012,.011464,
.011368,.011759,
.010695,.011939,
.01,.012,
-.01,.012,
-.010695,.011939,
-.011368,.011759,
-.012,.011464,
-.012571,.011064,
-.013064,.010571,
-.013464,.01,
-.013759,.009368,
-.013939,.008695,
-.014,.008,
0.0*
%
%ADD48MACRO48*%
%AMMACRO47*
4,1,40,-.0225,-.007,
-.022378,-.008389,
-.022018,-.009736,
-.021428,-.011,
-.020628,-.012142,
-.019642,-.013128,
-.0185,-.013928,
-.017236,-.014518,
-.015889,-.014878,
-.0145,-.015,
.0145,-.015,
.015889,-.014878,
.017236,-.014518,
.0185,-.013928,
.019642,-.013128,
.020628,-.012142,
.021428,-.011,
.022018,-.009736,
.022378,-.008389,
.0225,-.007,
.0225,.007,
.022378,.008389,
.022018,.009736,
.021428,.011,
.020628,.012142,
.019642,.013128,
.0185,.013928,
.017236,.014518,
.015889,.014878,
.0145,.015,
-.0145,.015,
-.015889,.014878,
-.017236,.014518,
-.0185,.013928,
-.019642,.013128,
-.020628,.012142,
-.021428,.011,
-.022018,.009736,
-.022378,.008389,
-.0225,.007,
-.0225,-.007,
0.0*
%
%ADD47MACRO47*%
%AMMACRO44*
4,1,40,-.007,.0225,
-.008389,.022378,
-.009736,.022018,
-.011,.021428,
-.012142,.020628,
-.013128,.019642,
-.013928,.0185,
-.014518,.017236,
-.014878,.015889,
-.015,.0145,
-.015,-.0145,
-.014878,-.015889,
-.014518,-.017236,
-.013928,-.0185,
-.013128,-.019642,
-.012142,-.020628,
-.011,-.021428,
-.009736,-.022018,
-.008389,-.022378,
-.007,-.0225,
.007,-.0225,
.008389,-.022378,
.009736,-.022018,
.011,-.021428,
.012142,-.020628,
.013128,-.019642,
.013928,-.0185,
.014518,-.017236,
.014878,-.015889,
.015,-.0145,
.015,.0145,
.014878,.015889,
.014518,.017236,
.013928,.0185,
.013128,.019642,
.012142,.020628,
.011,.021428,
.009736,.022018,
.008389,.022378,
.007,.0225,
-.007,.0225,
0.0*
%
%ADD44MACRO44*%
%AMMACRO24*
4,1,40,.012,.008,
.012,-.008,
.011939,-.008695,
.011759,-.009368,
.011464,-.01,
.011064,-.010571,
.010571,-.011064,
.01,-.011464,
.009368,-.011759,
.008695,-.011939,
.008,-.012,
-.008,-.012,
-.008695,-.011939,
-.009368,-.011759,
-.01,-.011464,
-.010571,-.011064,
-.011064,-.010571,
-.011464,-.01,
-.011759,-.009368,
-.011939,-.008695,
-.012,-.008,
-.012,.008,
-.011939,.008695,
-.011759,.009368,
-.011464,.01,
-.011064,.010571,
-.010571,.011064,
-.01,.011464,
-.009368,.011759,
-.008695,.011939,
-.008,.012,
.008,.012,
.008695,.011939,
.009368,.011759,
.01,.011464,
.010571,.011064,
.011064,.010571,
.011464,.01,
.011759,.009368,
.011939,.008695,
.012,.008,
0.0*
%
%ADD24MACRO24*%
%AMMACRO15*
4,1,40,-.007,.011,
.007,.011,
.007695,.010939,
.008368,.010759,
.009,.010464,
.009571,.010064,
.010064,.009571,
.010464,.009,
.010759,.008368,
.010939,.007695,
.011,.007,
.011,-.007,
.010939,-.007695,
.010759,-.008368,
.010464,-.009,
.010064,-.009571,
.009571,-.010064,
.009,-.010464,
.008368,-.010759,
.007695,-.010939,
.007,-.011,
-.007,-.011,
-.007695,-.010939,
-.008368,-.010759,
-.009,-.010464,
-.009571,-.010064,
-.010064,-.009571,
-.010464,-.009,
-.010759,-.008368,
-.010939,-.007695,
-.011,-.007,
-.011,.007,
-.010939,.007695,
-.010759,.008368,
-.010464,.009,
-.010064,.009571,
-.009571,.010064,
-.009,.010464,
-.008368,.010759,
-.007695,.010939,
-.007,.011,
0.0*
%
%ADD15MACRO15*%
%AMMACRO12*
4,1,40,.008,-.012,
-.008,-.012,
-.008695,-.011939,
-.009368,-.011759,
-.01,-.011464,
-.010571,-.011064,
-.011064,-.010571,
-.011464,-.01,
-.011759,-.009368,
-.011939,-.008695,
-.012,-.008,
-.012,.008,
-.011939,.008695,
-.011759,.009368,
-.011464,.01,
-.011064,.010571,
-.010571,.011064,
-.01,.011464,
-.009368,.011759,
-.008695,.011939,
-.008,.012,
.008,.012,
.008695,.011939,
.009368,.011759,
.01,.011464,
.010571,.011064,
.011064,.010571,
.011464,.01,
.011759,.009368,
.011939,.008695,
.012,.008,
.012,-.008,
.011939,-.008695,
.011759,-.009368,
.011464,-.01,
.011064,-.010571,
.010571,-.011064,
.01,-.011464,
.009368,-.011759,
.008695,-.011939,
.008,-.012,
0.0*
%
%ADD12MACRO12*%
%AMMACRO35*
4,1,40,.011,.007,
.011,-.007,
.010939,-.007695,
.010759,-.008368,
.010464,-.009,
.010064,-.009571,
.009571,-.010064,
.009,-.010464,
.008368,-.010759,
.007695,-.010939,
.007,-.011,
-.007,-.011,
-.007695,-.010939,
-.008368,-.010759,
-.009,-.010464,
-.009571,-.010064,
-.010064,-.009571,
-.010464,-.009,
-.010759,-.008368,
-.010939,-.007695,
-.011,-.007,
-.011,.007,
-.010939,.007695,
-.010759,.008368,
-.010464,.009,
-.010064,.009571,
-.009571,.010064,
-.009,.010464,
-.008368,.010759,
-.007695,.010939,
-.007,.011,
.007,.011,
.007695,.010939,
.008368,.010759,
.009,.010464,
.009571,.010064,
.010064,.009571,
.010464,.009,
.010759,.008368,
.010939,.007695,
.011,.007,
0.0*
%
%ADD35MACRO35*%
%AMMACRO21*
4,1,40,-.017,-.013,
-.017,.013,
-.016939,.013695,
-.016759,.014368,
-.016464,.015,
-.016064,.015571,
-.015571,.016064,
-.015,.016464,
-.014368,.016759,
-.013695,.016939,
-.013,.017,
.013,.017,
.013695,.016939,
.014368,.016759,
.015,.016464,
.015571,.016064,
.016064,.015571,
.016464,.015,
.016759,.014368,
.016939,.013695,
.017,.013,
.017,-.013,
.016939,-.013695,
.016759,-.014368,
.016464,-.015,
.016064,-.015571,
.015571,-.016064,
.015,-.016464,
.014368,-.016759,
.013695,-.016939,
.013,-.017,
-.013,-.017,
-.013695,-.016939,
-.014368,-.016759,
-.015,-.016464,
-.015571,-.016064,
-.016064,-.015571,
-.016464,-.015,
-.016759,-.014368,
-.016939,-.013695,
-.017,-.013,
0.0*
%
%ADD21MACRO21*%
%AMMACRO19*
4,1,40,.013,-.017,
-.013,-.017,
-.013695,-.016939,
-.014368,-.016759,
-.015,-.016464,
-.015571,-.016064,
-.016064,-.015571,
-.016464,-.015,
-.016759,-.014368,
-.016939,-.013695,
-.017,-.013,
-.017,.013,
-.016939,.013695,
-.016759,.014368,
-.016464,.015,
-.016064,.015571,
-.015571,.016064,
-.015,.016464,
-.014368,.016759,
-.013695,.016939,
-.013,.017,
.013,.017,
.013695,.016939,
.014368,.016759,
.015,.016464,
.015571,.016064,
.016064,.015571,
.016464,.015,
.016759,.014368,
.016939,.013695,
.017,.013,
.017,-.013,
.016939,-.013695,
.016759,-.014368,
.016464,-.015,
.016064,-.015571,
.015571,-.016064,
.015,-.016464,
.014368,-.016759,
.013695,-.016939,
.013,-.017,
0.0*
%
%ADD19MACRO19*%
%AMMACRO23*
4,1,40,.012,.008,
.012,-.008,
.011939,-.008695,
.011759,-.009368,
.011464,-.01,
.011064,-.010571,
.010571,-.011064,
.01,-.011464,
.009368,-.011759,
.008695,-.011939,
.008,-.012,
-.008,-.012,
-.008695,-.011939,
-.009368,-.011759,
-.01,-.011464,
-.010571,-.011064,
-.011064,-.010571,
-.011464,-.01,
-.011759,-.009368,
-.011939,-.008695,
-.012,-.008,
-.012,.008,
-.011939,.008695,
-.011759,.009368,
-.011464,.01,
-.011064,.010571,
-.010571,.011064,
-.01,.011464,
-.009368,.011759,
-.008695,.011939,
-.008,.012,
.008,.012,
.008695,.011939,
.009368,.011759,
.01,.011464,
.010571,.011064,
.011064,.010571,
.011464,.01,
.011759,.009368,
.011939,.008695,
.012,.008,
0.0*
%
%ADD23MACRO23*%
%AMMACRO16*
4,1,40,-.007,.011,
.007,.011,
.007695,.010939,
.008368,.010759,
.009,.010464,
.009571,.010064,
.010064,.009571,
.010464,.009,
.010759,.008368,
.010939,.007695,
.011,.007,
.011,-.007,
.010939,-.007695,
.010759,-.008368,
.010464,-.009,
.010064,-.009571,
.009571,-.010064,
.009,-.010464,
.008368,-.010759,
.007695,-.010939,
.007,-.011,
-.007,-.011,
-.007695,-.010939,
-.008368,-.010759,
-.009,-.010464,
-.009571,-.010064,
-.010064,-.009571,
-.010464,-.009,
-.010759,-.008368,
-.010939,-.007695,
-.011,-.007,
-.011,.007,
-.010939,.007695,
-.010759,.008368,
-.010464,.009,
-.010064,.009571,
-.009571,.010064,
-.009,.010464,
-.008368,.010759,
-.007695,.010939,
-.007,.011,
0.0*
%
%ADD16MACRO16*%
%AMMACRO11*
4,1,40,.008,-.012,
-.008,-.012,
-.008695,-.011939,
-.009368,-.011759,
-.01,-.011464,
-.010571,-.011064,
-.011064,-.010571,
-.011464,-.01,
-.011759,-.009368,
-.011939,-.008695,
-.012,-.008,
-.012,.008,
-.011939,.008695,
-.011759,.009368,
-.011464,.01,
-.011064,.010571,
-.010571,.011064,
-.01,.011464,
-.009368,.011759,
-.008695,.011939,
-.008,.012,
.008,.012,
.008695,.011939,
.009368,.011759,
.01,.011464,
.010571,.011064,
.011064,.010571,
.011464,.01,
.011759,.009368,
.011939,.008695,
.012,.008,
.012,-.008,
.011939,-.008695,
.011759,-.009368,
.011464,-.01,
.011064,-.010571,
.010571,-.011064,
.01,-.011464,
.009368,-.011759,
.008695,-.011939,
.008,-.012,
0.0*
%
%ADD11MACRO11*%
%ADD54C,.02*%
%ADD55C,.006*%
G75*
%LPD*%
G75*
G54D10*
X30900Y79600D03*
X81169Y734566D03*
X847271Y45720D03*
G54D11*
X65400Y546000D03*
X100619Y564385D03*
X97113Y564386D03*
X92870Y564415D03*
X78247Y562479D03*
X137100Y597000D03*
X133600D03*
X207600Y495580D03*
X327538Y600224D03*
X689875Y468836D03*
X686496Y512847D03*
X690134Y512896D03*
X693692Y512862D03*
X765453Y525125D03*
X786667Y511552D03*
X782667D03*
X760375Y525096D03*
X756375D03*
X769453Y525125D03*
X773453D03*
X790667Y511552D03*
X794667D03*
G54D20*
X47468Y567316D03*
X54850Y580250D03*
X102500Y712200D03*
X195371Y559210D03*
X202630Y583440D03*
X876590Y222573D03*
G54D21*
X64350Y582500D03*
X129100Y602100D03*
X141189Y601337D03*
X148840Y555135D03*
X153495Y555166D03*
X213000Y522800D03*
X245100Y635800D03*
X354000Y637700D03*
X349200D03*
X377714Y627580D03*
X375600Y604200D03*
G54D12*
X65400Y549600D03*
X78247Y566079D03*
X137100Y600600D03*
X133600D03*
X100619Y567985D03*
X97113Y567986D03*
X92870Y568015D03*
X207600Y499180D03*
X327538Y603824D03*
X689875Y472436D03*
X686496Y516447D03*
X690134Y516496D03*
X693692Y516462D03*
X765453Y528725D03*
X786667Y515152D03*
X782667D03*
X760375Y528696D03*
X756375D03*
X769453Y528725D03*
X773453D03*
X790667Y515152D03*
X794667D03*
G54D30*
X99874Y535824D03*
X86200Y677300D03*
X175548Y568251D03*
X186489Y582625D03*
X286211Y553256D03*
X860686Y159490D03*
X872998Y391533D03*
G54D31*
X100130Y576452D03*
X85700Y681400D03*
X171969Y579940D03*
X211700Y638400D03*
X216200Y467300D03*
X222019Y634188D03*
X297800Y527900D03*
X328123Y579949D03*
X698225Y445986D03*
X687000Y496509D03*
Y500209D03*
X883986Y269745D03*
X861498Y348715D03*
G54D40*
X141887Y560491D03*
X146567Y560391D03*
X151257Y560423D03*
X203000Y517200D03*
X198000D03*
X208000D03*
X144037Y549486D03*
X197230Y571870D03*
X181505Y575791D03*
X160964Y717468D03*
X218000Y517200D03*
X493500Y53700D03*
X446403Y31900D03*
X506500Y53700D03*
X860504Y168244D03*
X861511Y357363D03*
G54D13*
X64151Y517477D03*
X64251Y509877D03*
X120273Y500759D03*
X86659Y517477D03*
X86673Y510000D03*
X81032Y517477D03*
X81068Y509866D03*
X92286Y517477D03*
X92273Y510000D03*
X97913Y517477D03*
X97900Y510000D03*
X69778Y517477D03*
X69878Y509777D03*
X75405Y517477D03*
X75373Y509879D03*
X121643Y618027D03*
X148000Y475500D03*
X143700D03*
X152589Y489481D03*
X192300Y493500D03*
X212118Y470993D03*
X167000Y520500D03*
X146700Y530100D03*
X156501Y564267D03*
X162700Y495700D03*
X158600Y528400D03*
X167454Y530877D03*
X163300Y530600D03*
X174900Y506500D03*
X200910Y563190D03*
X179400Y531800D03*
X183670Y531766D03*
X196013Y536175D03*
X146600Y520700D03*
X196890Y567300D03*
X184400Y611300D03*
X212500Y611900D03*
X155341Y616572D03*
X196500Y611300D03*
X194718Y625994D03*
X184700Y591000D03*
X218500Y490700D03*
X273809Y563811D03*
X215448Y535601D03*
X269709Y563813D03*
X224000Y622700D03*
X238100Y586400D03*
X252300Y580700D03*
X242100Y586400D03*
X296680Y556264D03*
X288286Y579720D03*
X309765Y603700D03*
X344102Y594663D03*
X312000Y666700D03*
X307849Y668900D03*
X358120Y547604D03*
X357500Y566900D03*
X369800Y578000D03*
X380000Y601800D03*
X357655Y681145D03*
X521330Y85580D03*
X815016Y348514D03*
X819100Y393600D03*
G54D22*
X64350Y576900D03*
X129100Y596500D03*
X141189Y595737D03*
X148840Y549535D03*
X153495Y549566D03*
X213000Y517200D03*
X245100Y630200D03*
X354000Y632100D03*
X349200D03*
X377714Y621980D03*
X375600Y598600D03*
G54D23*
X127400Y504600D03*
X152316Y570305D03*
X175579Y583387D03*
X207500Y634400D03*
X254800Y609800D03*
X288336Y598419D03*
X359489Y540188D03*
X369409Y509699D03*
X365780Y551390D03*
X671232Y486702D03*
Y490702D03*
Y494202D03*
Y482602D03*
G54D41*
X141887Y566091D03*
X146567Y565991D03*
X151257Y566023D03*
X203000Y522800D03*
X198000D03*
X208000D03*
X144037Y555086D03*
X197230Y577470D03*
X181505Y581391D03*
X160964Y723068D03*
X218000Y522800D03*
X493500Y59300D03*
X446403Y37500D03*
X506500Y59300D03*
X860504Y173844D03*
X861511Y362963D03*
G54D14*
X64151Y514077D03*
X64251Y506477D03*
X120273Y497359D03*
X86659Y514077D03*
X86673Y506600D03*
X81032Y514077D03*
X81068Y506466D03*
X92286Y514077D03*
X92273Y506600D03*
X97913Y514077D03*
X97900Y506600D03*
X69778Y514077D03*
X69878Y506377D03*
X75405Y514077D03*
X75373Y506479D03*
X121643Y614627D03*
X162700Y492300D03*
X148000Y472100D03*
X143700D03*
X152589Y486081D03*
X192300Y490100D03*
X212118Y467593D03*
X167000Y517100D03*
X146700Y526700D03*
X156501Y560867D03*
X196890Y563900D03*
X158600Y525000D03*
X167454Y527477D03*
X163300Y527200D03*
X174900Y503100D03*
X200910Y559790D03*
X179400Y528400D03*
X183670Y528366D03*
X196013Y532775D03*
X146600Y517300D03*
X184400Y607900D03*
X212500Y608500D03*
X155341Y613172D03*
X196500Y607900D03*
X194718Y622594D03*
X184700Y587600D03*
X218500Y487300D03*
X273809Y560411D03*
X215448Y532201D03*
X269709Y560413D03*
X224000Y619300D03*
X238100Y583000D03*
X252300Y577300D03*
X242100Y583000D03*
X296680Y552864D03*
X288286Y576320D03*
X309765Y600300D03*
X344102Y591263D03*
X312000Y663300D03*
X307849Y665500D03*
X357500Y563500D03*
X358120Y544204D03*
X369800Y574600D03*
X380000Y598400D03*
X357655Y677745D03*
X521330Y82180D03*
X815016Y345114D03*
X819100Y390200D03*
G54D32*
X103730Y576452D03*
X89300Y681400D03*
X175569Y579940D03*
X219800Y467300D03*
X225619Y634188D03*
X215300Y638400D03*
X301400Y527900D03*
X331723Y579949D03*
X701825Y445986D03*
X690600Y496509D03*
Y500209D03*
X887586Y269745D03*
X865098Y348715D03*
G54D50*
X526025Y64390D03*
X518275D03*
X522150Y71890D03*
X824116Y334544D03*
X827991Y327044D03*
X820241D03*
G54D15*
X49306Y532622D03*
X41865Y532638D03*
X49385Y555153D03*
X41885D03*
X49306Y538249D03*
X41758Y538254D03*
X49306Y543876D03*
X41858Y543881D03*
X49306Y526995D03*
X41875D03*
X49306Y521269D03*
X41832Y521271D03*
X49385Y549526D03*
X41903Y549508D03*
X49385Y560879D03*
X41800Y560900D03*
X58500Y575850D03*
X54156Y571795D03*
X140400Y479700D03*
Y483900D03*
X116172Y497305D03*
X128200Y610500D03*
X129800Y630800D03*
Y634900D03*
Y639000D03*
X200200Y489500D03*
X174900Y530700D03*
X160289Y520812D03*
X187680Y520045D03*
X187238Y536101D03*
X178086Y513171D03*
X150503Y509389D03*
X197100Y528500D03*
X175487Y587147D03*
X188110Y617688D03*
X190104Y636190D03*
X197570Y636210D03*
X151700Y590500D03*
X207000Y642300D03*
X191245Y642681D03*
X199100Y642800D03*
X219700Y471100D03*
X228425Y484151D03*
X252400Y543600D03*
X242920Y562521D03*
X219453Y528088D03*
X225508Y637894D03*
X215200Y634500D03*
X227548Y581666D03*
X238900Y597500D03*
X268700Y588500D03*
X252900Y571100D03*
Y567100D03*
X245130Y571032D03*
X244830Y566732D03*
X296520Y561123D03*
X347600Y574900D03*
X318022Y606283D03*
X307800Y661300D03*
X377200Y31000D03*
X365700Y574900D03*
X360933Y673696D03*
X360800Y665580D03*
X461660Y25990D03*
X493660Y37883D03*
X441400Y37800D03*
X521290Y77700D03*
X699744Y480189D03*
X754979Y538718D03*
X770194Y540231D03*
X762705Y538797D03*
X831439Y340820D03*
X816896Y428321D03*
G54D24*
X123800Y504600D03*
X148716Y570305D03*
X171979Y583387D03*
X203900Y634400D03*
X251200Y609800D03*
X284736Y598419D03*
X355889Y540188D03*
X365809Y509699D03*
X362180Y551390D03*
X667632Y486702D03*
Y490702D03*
Y494202D03*
Y482602D03*
G54D51*
X695210Y460886D03*
X697770D03*
X700330D03*
X702890D03*
Y473686D03*
X700330D03*
X697770D03*
X695210D03*
X811748Y409837D03*
X814308D03*
X816868D03*
X819428D03*
Y422637D03*
X816868D03*
X814308D03*
X811748D03*
G54D33*
X96287Y576499D03*
X143823Y615646D03*
X250300Y633600D03*
X354662Y523046D03*
X308700Y515500D03*
X360980Y590486D03*
X586447Y60807D03*
X815334Y393662D03*
X806825Y424215D03*
G36*
G01X175989Y669266D02*
G02Y669316I-12800J25D01*
G01X171589D01*
G03Y669266I-8400J-25D01*
G01X175989D01*
G37*
G54D16*
X45906Y532622D03*
X38465Y532638D03*
X45985Y555153D03*
X38485D03*
X45906Y538249D03*
X38358Y538254D03*
X45906Y543876D03*
X38458Y543881D03*
X45906Y526995D03*
X38475D03*
X45906Y521269D03*
X38432Y521271D03*
X45985Y549526D03*
X38503Y549508D03*
X45985Y560879D03*
X38400Y560900D03*
X55100Y575850D03*
X50756Y571795D03*
X137000Y479700D03*
Y483900D03*
X112772Y497305D03*
X124800Y610500D03*
X126400Y630800D03*
Y634900D03*
Y639000D03*
X196800Y489500D03*
X171500Y530700D03*
X156889Y520812D03*
X184280Y520045D03*
X183838Y536101D03*
X174686Y513171D03*
X147103Y509389D03*
X193700Y528500D03*
X211800Y634500D03*
X172087Y587147D03*
X184710Y617688D03*
X186704Y636190D03*
X194170Y636210D03*
X148300Y590500D03*
X203600Y642300D03*
X187845Y642681D03*
X195700Y642800D03*
X216300Y471100D03*
X225025Y484151D03*
X249000Y543600D03*
X239520Y562521D03*
X216053Y528088D03*
X222108Y637894D03*
X224148Y581666D03*
X235500Y597500D03*
X265300Y588500D03*
X249500Y571100D03*
Y567100D03*
X241730Y571032D03*
X241430Y566732D03*
X293120Y561123D03*
X344200Y574900D03*
X314622Y606283D03*
X304400Y661300D03*
X373800Y31000D03*
X362300Y574900D03*
X357533Y673696D03*
X357400Y665580D03*
X458260Y25990D03*
X490260Y37883D03*
X438000Y37800D03*
X517890Y77700D03*
X696344Y480189D03*
X751579Y538718D03*
X766794Y540231D03*
X759305Y538797D03*
X828039Y340820D03*
X813496Y428321D03*
G54D25*
X137824Y544746D03*
Y552346D03*
X135449Y558949D03*
Y566549D03*
X122600Y594800D03*
Y602400D03*
X149700Y723000D03*
Y715400D03*
X228201Y518368D03*
Y510768D03*
X249500Y616500D03*
Y624100D03*
X241800Y624000D03*
Y616400D03*
X311057Y193874D03*
Y201474D03*
X318763Y220690D03*
Y228290D03*
X311097Y220715D03*
Y228315D03*
X329435Y225684D03*
Y218084D03*
X477343Y33619D03*
Y41219D03*
X663847Y39907D03*
Y32307D03*
X655847Y39907D03*
Y32307D03*
X677447Y478527D03*
Y470927D03*
X699365Y510653D03*
Y518253D03*
X749875Y523096D03*
Y530696D03*
X779239Y522260D03*
Y529860D03*
X800291Y509468D03*
Y517068D03*
X885359Y223815D03*
Y216215D03*
X901690Y397644D03*
Y405244D03*
X894072Y397625D03*
Y405225D03*
X866541Y392586D03*
Y400186D03*
G54D43*
X214040Y504230D03*
X216600D03*
X219160D03*
Y497730D03*
X214040D03*
G54D34*
X96287Y572899D03*
X143823Y612046D03*
X250300Y630000D03*
X354662Y519446D03*
X308700Y511900D03*
X360980Y586886D03*
X586447Y57207D03*
X806825Y420615D03*
X815334Y390062D03*
G54D52*
X850567Y383181D03*
G54D35*
X133600Y614300D03*
X204800Y487100D03*
X166761Y492320D03*
X212165Y483008D03*
X191694Y532628D03*
X170800Y503100D03*
X211378Y532401D03*
X166737Y502154D03*
X179000Y503100D03*
X207278Y532401D03*
X162537Y502154D03*
X200031Y532794D03*
X147247Y501787D03*
X151351Y501797D03*
X158294Y502154D03*
X192471Y610938D03*
X188431Y609938D03*
X147723Y612196D03*
X217908Y479635D03*
X222100Y475200D03*
X233300Y543700D03*
X237300D03*
X246980Y558568D03*
X219473Y532173D03*
X221800Y608300D03*
X225900Y608200D03*
X273895Y567952D03*
X272900Y584300D03*
X242600Y575100D03*
X269806Y567952D03*
X330600Y505900D03*
X288286Y583855D03*
X351500Y584090D03*
X314800Y678000D03*
X357000Y586800D03*
X373400Y622600D03*
X498150Y55330D03*
X459610Y33640D03*
X493500Y63900D03*
X511500Y54800D03*
X837816Y344414D03*
X848820Y400072D03*
G54D44*
X340631Y384824D03*
X336756Y392324D03*
X344506D03*
G54D53*
X853267Y383181D03*
G54D26*
X78525Y554363D03*
X78524Y558398D03*
X98044Y555240D03*
X98076Y560166D03*
X139800Y620200D03*
X126200Y626300D03*
X184800Y489000D03*
X199400Y483000D03*
X168101Y469168D03*
Y473268D03*
X171500Y526700D03*
X198846Y501509D03*
X200600Y608800D03*
X172402Y574058D03*
X198755Y625814D03*
X159700Y619900D03*
X149557Y602562D03*
X145800Y596700D03*
X204000Y638200D03*
X176034Y619120D03*
X147600Y620200D03*
X211700Y642200D03*
X241400Y543700D03*
X226357Y534556D03*
X238000Y556100D03*
Y551900D03*
X229700Y505300D03*
X255861Y548308D03*
X247600Y536200D03*
X255200Y535800D03*
X235500Y593500D03*
X228192Y622802D03*
X223000Y597200D03*
Y593200D03*
X224000Y571900D03*
X224375Y576816D03*
X224300Y585900D03*
X228000Y567000D03*
X265300Y584500D03*
X263288Y666467D03*
X222092Y642006D03*
X328100Y387774D03*
X342200Y377800D03*
X320725Y558073D03*
X324585Y566198D03*
X344200Y579231D03*
X324756Y571267D03*
X305817Y682959D03*
X362280Y544200D03*
X375915Y617425D03*
X357435Y661505D03*
X493818Y42607D03*
X490250Y33781D03*
X507300Y65000D03*
X535006Y68742D03*
X700891Y484208D03*
X693400Y455000D03*
X698300Y442100D03*
X825100Y422612D03*
X811481Y403117D03*
G54D17*
X31100Y512700D03*
X37500Y579400D03*
X126330Y445098D03*
X108492Y541948D03*
X102500Y499700D03*
X130400Y539900D03*
X126780Y562773D03*
X134800Y604800D03*
X137100Y589427D03*
X117121Y579999D03*
X139400Y615000D03*
X134354Y632246D03*
X94818Y655471D03*
X118998Y701124D03*
X115598Y708228D03*
X133000Y656400D03*
X89560Y712200D03*
X109478Y713245D03*
X183900Y493100D03*
X147100Y483400D03*
X144943Y480031D03*
X178500Y492200D03*
X167999Y479200D03*
X149000Y494500D03*
X207300Y471520D03*
X208400Y476900D03*
X207500Y483000D03*
X176252Y473571D03*
X176224Y468472D03*
X174036Y448700D03*
X151016Y445380D03*
X181938Y444600D03*
X190999Y446650D03*
X145000Y492200D03*
X187964Y493426D03*
X197847Y494417D03*
X187699Y543279D03*
X187800Y547278D03*
X178200Y540400D03*
X209627Y540605D03*
X163300Y510400D03*
X174930Y534600D03*
X164784Y539407D03*
X167000Y535500D03*
X158200Y532900D03*
X190936Y540928D03*
X177600Y517400D03*
X198796Y505657D03*
X200402Y542169D03*
X203930Y540283D03*
X154400Y524400D03*
X203356Y495487D03*
X199162Y602800D03*
X152640Y582742D03*
X184932Y601225D03*
X180571Y611325D03*
X177200Y633500D03*
X172449Y633644D03*
X156500Y598500D03*
X190944Y605862D03*
X199950Y617600D03*
X195500Y618000D03*
X200500Y622000D03*
X206800Y627047D03*
X207450Y622000D03*
X208423Y605303D03*
X165000Y614300D03*
X161047Y615989D03*
X160088Y608100D03*
X159500Y612300D03*
X153000Y594927D03*
X148400Y607000D03*
X179344Y607509D03*
X155950Y592010D03*
X162500Y624850D03*
X173247Y607000D03*
X172848Y700108D03*
X155846Y723282D03*
X280587Y491768D03*
X280700Y484600D03*
X239100Y450500D03*
X223146Y489341D03*
X267435Y442572D03*
X245800Y443600D03*
X215300Y512200D03*
X235002Y562120D03*
X224600Y560900D03*
X230277Y559321D03*
X214235Y539198D03*
X246400Y547900D03*
X246463Y553137D03*
X224900Y497730D03*
X260000Y517300D03*
X279654Y497255D03*
X279000Y555000D03*
X252500Y563200D03*
X229807Y530200D03*
X224000Y539130D03*
X225500Y557000D03*
X258300Y504750D03*
X256500Y552900D03*
X240274Y629709D03*
X213400Y621100D03*
X219466Y628146D03*
X251100Y595000D03*
X236400Y568800D03*
X265231Y570631D03*
X237500Y578550D03*
X236800Y574297D03*
X218300Y605000D03*
X221000Y601900D03*
X215900Y595500D03*
X232536Y588078D03*
X218298Y591749D03*
X226195Y603279D03*
X264750Y580250D03*
X247400Y576400D03*
X260096Y574693D03*
X249361Y693100D03*
X218925Y666220D03*
X267584Y656531D03*
X250128Y678106D03*
X250900Y642100D03*
X331321Y198570D03*
X334200Y205400D03*
X335100Y237500D03*
X315866Y214556D03*
X328451Y207719D03*
X312800Y244461D03*
X321900Y249400D03*
X324600Y252600D03*
X330806Y392324D03*
X339507Y433648D03*
X351597Y438869D03*
X354158Y430400D03*
X293800Y534000D03*
X292200Y548564D03*
X308253Y535182D03*
X290590Y509859D03*
X331806Y561752D03*
X328012Y556569D03*
X318970Y565209D03*
X337600Y515500D03*
X339300Y526300D03*
X331240Y500920D03*
X331600Y512900D03*
X334900Y557600D03*
X316700Y631700D03*
X355200Y607700D03*
X345386Y604896D03*
X319401Y569678D03*
X347398Y599694D03*
X309765Y608200D03*
X348161Y592261D03*
X319831Y573790D03*
X315411Y701965D03*
X352600Y674489D03*
X290951Y673641D03*
X352557Y679888D03*
X317159Y667813D03*
X311798Y673233D03*
X325332Y685592D03*
X316550Y663250D03*
X327368Y651299D03*
X310100Y677950D03*
X297330Y682986D03*
X313000Y658500D03*
X291754Y680486D03*
X365000Y75500D03*
X383700Y500800D03*
X357379Y552518D03*
X357853Y500825D03*
X374049Y517383D03*
X357400Y559500D03*
X375000Y573200D03*
X385700Y586100D03*
X376676Y568400D03*
X488800Y62100D03*
X461350Y29800D03*
X443869Y43095D03*
X488974Y44580D03*
X483091Y33900D03*
X452490Y64240D03*
X457585Y70015D03*
X544309Y39634D03*
X563620Y60160D03*
X530031Y32071D03*
X508855Y40905D03*
X534956Y62900D03*
X502400Y64400D03*
X588200Y44800D03*
X591347Y53907D03*
X603847Y60757D03*
X633137Y19759D03*
X579158Y73212D03*
X648910Y40090D03*
X669505Y41254D03*
X700689Y491390D03*
X704486Y488179D03*
X697100Y450200D03*
X681500Y501000D03*
X775100Y540000D03*
X754829Y502218D03*
X724242Y504713D03*
X764254Y544790D03*
X851008Y186924D03*
X853697Y161250D03*
X852922Y207800D03*
X834116Y330314D03*
X813916Y338614D03*
X846295Y383181D03*
X848820Y395572D03*
X839643Y390800D03*
X836284Y352842D03*
X835820Y380672D03*
X815600Y398300D03*
X825000Y428800D03*
X829700Y426800D03*
X798600Y502500D03*
X792300Y502200D03*
X860486Y163694D03*
X870228Y217843D03*
X899400Y235700D03*
X898300Y284200D03*
X870447Y281493D03*
X870568Y302548D03*
X866800Y406100D03*
X887718Y375178D03*
X861511Y352861D03*
X900379Y391262D03*
X860398Y394819D03*
G54D54*
G01X-36569Y-23804D02*
Y-103804D01*
G01D02*
X1258031D01*
G01X-40569Y-7804D02*
G02I-12000J0D01*
G01X-45719D02*
G02I-6850J0D01*
G01X-52569Y-23804D02*
Y8196D01*
G01X-36569Y-23804D02*
X1258031D01*
G01X-36569Y-59304D02*
X1258031D01*
G01X-36569Y-7804D02*
X-68569D01*
G01X470531Y-23804D02*
Y-103804D01*
G01X608031Y-23804D02*
Y-103804D01*
G01X723031Y-23804D02*
Y-103804D01*
G01X890531Y-23804D02*
Y-103804D01*
G01X1060531Y-23804D02*
Y-103804D01*
G01X1258031Y-23804D02*
Y-103804D01*
G01X1286031Y-7804D02*
G02I-12000J0D01*
G01X1280881D02*
G02I-6850J0D01*
G01X1274031Y-23804D02*
Y8196D01*
G01X1290031Y-7804D02*
X1258031D01*
G54D18*
X54100Y586350D03*
X46500D03*
X100100Y705700D03*
X92500D03*
X325629Y183698D03*
X318029D03*
X325705Y191549D03*
X318105D03*
X328900Y235400D03*
X321300D03*
X685200Y490609D03*
X692800D03*
X888326Y201329D03*
X895926D03*
X885501Y209131D03*
X893101D03*
X869245Y212185D03*
X861645D03*
X881986Y275745D03*
X889586D03*
X881986Y299745D03*
X889586D03*
X881986Y307745D03*
X889586D03*
X881986Y291745D03*
X889586D03*
X881986Y283745D03*
X889586D03*
X885914Y398288D03*
X878314D03*
G54D27*
X81925Y554363D03*
X81924Y558398D03*
X101444Y555240D03*
X101476Y560166D03*
X129600Y626300D03*
X188200Y489000D03*
X202800Y483000D03*
X171501Y469168D03*
Y473268D03*
X174900Y526700D03*
X202246Y501509D03*
X204000Y608800D03*
X175802Y574058D03*
X202155Y625814D03*
X163100Y619900D03*
X152957Y602562D03*
X149200Y596700D03*
X207400Y638200D03*
X179434Y619120D03*
X143200Y620200D03*
X151000D03*
X244800Y543700D03*
X229757Y534556D03*
X241400Y556100D03*
Y551900D03*
X233100Y505300D03*
X259261Y548308D03*
X251000Y536200D03*
X258600Y535800D03*
X238900Y593500D03*
X231592Y622802D03*
X226400Y597200D03*
Y593200D03*
X227400Y571900D03*
X227775Y576816D03*
X227700Y585900D03*
X231400Y567000D03*
X268700Y584500D03*
X266688Y666467D03*
X215100Y642200D03*
X225492Y642006D03*
X331500Y387774D03*
X345600Y377800D03*
X324125Y558073D03*
X327985Y566198D03*
X347600Y579231D03*
X328156Y571267D03*
X309217Y682959D03*
X365680Y544200D03*
X379315Y617425D03*
X360835Y661505D03*
X497218Y42607D03*
X493650Y33781D03*
X510700Y65000D03*
X538406Y68742D03*
X704291Y484208D03*
X696800Y455000D03*
X701700Y442100D03*
X828500Y422612D03*
X814881Y403117D03*
G54D45*
X354800Y612600D03*
X351200D03*
G54D36*
X133600Y617700D03*
X204800Y490500D03*
X212165Y486408D03*
X191694Y536028D03*
X170800Y506500D03*
X166761Y495720D03*
X211378Y535801D03*
X166737Y505554D03*
X179000Y506500D03*
X207278Y535801D03*
X162537Y505554D03*
X200031Y536194D03*
X147247Y505187D03*
X151351Y505197D03*
X158294Y505554D03*
X192471Y614338D03*
X188431Y613338D03*
X147723Y615596D03*
X217908Y483035D03*
X222100Y478600D03*
X233300Y547100D03*
X237300D03*
X246980Y561968D03*
X219473Y535573D03*
X221800Y611700D03*
X225900Y611600D03*
X273895Y571352D03*
X272900Y587700D03*
X242600Y578500D03*
X269806Y571352D03*
X330600Y509300D03*
X288286Y587255D03*
X351500Y587490D03*
X314800Y681400D03*
X357000Y590200D03*
X373400Y626000D03*
X498150Y58730D03*
X459610Y37040D03*
X493500Y67300D03*
X511500Y58200D03*
X837816Y347814D03*
X848820Y403472D03*
G54D55*
G01X-9023Y-84471D02*
X-8149Y-83596D01*
X-7494Y-82138D01*
X-7057Y-80095D01*
X-7494Y-78346D01*
X-8367Y-77179D01*
X-9896Y-76304D01*
X-15791D01*
Y-93804D01*
X-8586D01*
X-7057Y-92638D01*
X-6184Y-90887D01*
X-5747Y-88846D01*
X-6184Y-86804D01*
X-7494Y-85054D01*
X-9023Y-84471D01*
X-15791D01*
G01X3674Y-93804D02*
Y-82138D01*
G01Y-84471D02*
X4766Y-83304D01*
X5858Y-82429D01*
X7386Y-82138D01*
X8477Y-82429D01*
X9788Y-83304D01*
G01X19646Y-99054D02*
X20956Y-99637D01*
X22703Y-99054D01*
X23794Y-97888D01*
X24668Y-96429D01*
X25977Y-91763D01*
X28816Y-82138D01*
G01X21829D02*
X25977Y-91763D01*
G01X45224Y-83596D02*
X43696Y-82429D01*
X42386Y-82138D01*
X40639Y-82721D01*
X39329Y-83887D01*
X38456Y-85929D01*
X38237Y-87971D01*
X38456Y-90013D01*
X39329Y-91763D01*
X40639Y-93221D01*
X42386Y-93804D01*
X43914Y-93221D01*
X45224Y-92054D01*
G01X55956Y-85929D02*
X62943D01*
X62288Y-83887D01*
X61196Y-82721D01*
X59668Y-82138D01*
X58139Y-82429D01*
X56829Y-83304D01*
X55956Y-85346D01*
X55519Y-87096D01*
Y-88846D01*
X55956Y-90596D01*
X57048Y-92346D01*
X58358Y-93512D01*
X59886Y-93804D01*
X61414Y-93221D01*
X62943Y-91471D01*
G01X99034Y-77763D02*
X97724Y-76887D01*
X96196Y-76304D01*
X94449D01*
X92484Y-77179D01*
X90956Y-78637D01*
X89864Y-80388D01*
X88991Y-83304D01*
X88772Y-85929D01*
X89209Y-88554D01*
X89864Y-90304D01*
X91174Y-92054D01*
X92703Y-93221D01*
X94231Y-93804D01*
X95759D01*
X97288Y-93221D01*
X98598Y-92346D01*
X99690Y-91180D01*
G01X115661Y-93804D02*
Y-82138D01*
G01Y-84179D02*
X114788Y-83013D01*
X113477Y-82429D01*
X111949Y-82138D01*
X110421Y-82721D01*
X109111Y-83887D01*
X108237Y-85637D01*
X107801Y-87971D01*
X108237Y-90304D01*
X109111Y-92054D01*
X110421Y-93221D01*
X111949Y-93804D01*
X113477Y-93512D01*
X114788Y-92638D01*
X115661Y-91471D01*
G01X125519Y-93804D02*
Y-82138D01*
G01Y-85054D02*
X126393Y-83596D01*
X127703Y-82429D01*
X129449Y-82138D01*
X130977Y-82429D01*
X132288Y-83596D01*
X132943Y-85637D01*
Y-93804D01*
G01X142146Y-99054D02*
X143456Y-99637D01*
X145203Y-99054D01*
X146294Y-97888D01*
X147168Y-96429D01*
X148477Y-91763D01*
X151316Y-82138D01*
G01X144329D02*
X148477Y-91763D01*
G01X164231Y-93804D02*
X162921Y-93512D01*
X161611Y-92346D01*
X160737Y-90304D01*
X160301Y-87971D01*
X160737Y-85637D01*
X161611Y-83596D01*
X162921Y-82429D01*
X164231Y-82138D01*
X165541Y-82429D01*
X166851Y-83596D01*
X167724Y-85637D01*
X167943Y-87971D01*
X167724Y-90304D01*
X166851Y-92346D01*
X165541Y-93512D01*
X164231Y-93804D01*
G01X178019D02*
Y-82138D01*
G01Y-85054D02*
X178893Y-83596D01*
X180203Y-82429D01*
X181949Y-82138D01*
X183477Y-82429D01*
X184788Y-83596D01*
X185443Y-85637D01*
Y-93804D01*
G01X214111Y-76304D02*
X219351D01*
G01X216731D02*
Y-93804D01*
G01X214111D02*
X219351D01*
G01X234231D02*
X232484Y-93512D01*
X230956Y-92346D01*
X229646Y-90596D01*
X228772Y-88554D01*
X228336Y-86221D01*
Y-83887D01*
X228772Y-81554D01*
X229646Y-79512D01*
X230956Y-77763D01*
X232484Y-76596D01*
X234231Y-76304D01*
X235977Y-76596D01*
X237506Y-77763D01*
X238816Y-79512D01*
X239690Y-81554D01*
X240126Y-83887D01*
Y-86221D01*
X239690Y-88554D01*
X238816Y-90596D01*
X237506Y-92346D01*
X235977Y-93512D01*
X234231Y-93804D01*
G01X246054D02*
Y-76304D01*
X251731Y-90887D01*
X257408Y-76304D01*
Y-93804D01*
G01X285639Y-99637D02*
X283456Y-96721D01*
X282364Y-93804D01*
Y-82138D01*
X283456Y-79221D01*
X285639Y-76304D01*
G01X298554Y-93804D02*
Y-76304D01*
X304231Y-90887D01*
X309908Y-76304D01*
Y-93804D01*
G01X321731Y-94387D02*
X321294Y-94096D01*
Y-93512D01*
X321731Y-93221D01*
X322168Y-93512D01*
Y-94096D01*
X321731Y-94387D01*
G01X335083Y-79221D02*
X336393Y-77471D01*
X337921Y-76596D01*
X339668Y-76304D01*
X341851Y-76887D01*
X343379Y-78346D01*
X343816Y-80095D01*
X343598Y-81846D01*
X342724Y-83304D01*
X338358Y-86221D01*
X336393Y-88262D01*
X335083Y-91180D01*
X334646Y-93804D01*
X343816D01*
G01X374231D02*
X372921Y-93512D01*
X371611Y-92346D01*
X370737Y-90304D01*
X370301Y-87971D01*
X370737Y-85637D01*
X371611Y-83596D01*
X372921Y-82429D01*
X374231Y-82138D01*
X375541Y-82429D01*
X376851Y-83596D01*
X377724Y-85637D01*
X377943Y-87971D01*
X377724Y-90304D01*
X376851Y-92346D01*
X375541Y-93512D01*
X374231Y-93804D01*
G01X388019D02*
Y-82138D01*
G01Y-85054D02*
X388893Y-83596D01*
X390203Y-82429D01*
X391949Y-82138D01*
X393477Y-82429D01*
X394788Y-83596D01*
X395443Y-85637D01*
Y-93804D01*
G01X409231D02*
Y-76304D01*
G01X422146Y-99054D02*
X423456Y-99637D01*
X425203Y-99054D01*
X426294Y-97888D01*
X427168Y-96429D01*
X428477Y-91763D01*
X431316Y-82138D01*
G01X424329D02*
X428477Y-91763D01*
G01X445323Y-99637D02*
X447506Y-96721D01*
X448598Y-93804D01*
Y-82138D01*
X447506Y-79221D01*
X445323Y-76304D01*
G01X176054Y-48804D02*
Y-31304D01*
X181731Y-45887D01*
X187408Y-31304D01*
Y-48804D01*
G01X199231D02*
X197921Y-48512D01*
X196611Y-47346D01*
X195737Y-45304D01*
X195301Y-42971D01*
X195737Y-40637D01*
X196611Y-38596D01*
X197921Y-37429D01*
X199231Y-37138D01*
X200541Y-37429D01*
X201851Y-38596D01*
X202724Y-40637D01*
X202943Y-42971D01*
X202724Y-45304D01*
X201851Y-47346D01*
X200541Y-48512D01*
X199231Y-48804D01*
G01X220661Y-31304D02*
Y-48804D01*
G01Y-46180D02*
X219788Y-47638D01*
X218477Y-48512D01*
X216949Y-48804D01*
X215203Y-48221D01*
X213893Y-46763D01*
X213019Y-45013D01*
X212801Y-42971D01*
X213019Y-40929D01*
X213893Y-39179D01*
X215203Y-37721D01*
X216949Y-37138D01*
X218477Y-37429D01*
X219569Y-38013D01*
X220661Y-39179D01*
G01X230956Y-40929D02*
X237943D01*
X237288Y-38887D01*
X236196Y-37721D01*
X234668Y-37138D01*
X233139Y-37429D01*
X231829Y-38304D01*
X230956Y-40346D01*
X230519Y-42096D01*
Y-43846D01*
X230956Y-45596D01*
X232048Y-47346D01*
X233358Y-48512D01*
X234886Y-48804D01*
X236414Y-48221D01*
X237943Y-46471D01*
G01X251731Y-48804D02*
Y-31304D01*
G01X504231Y-93804D02*
Y-76304D01*
X501611Y-79804D01*
G01Y-93804D02*
X506851D01*
G01X517583Y-86513D02*
X519111Y-84471D01*
X520421Y-83304D01*
X522168Y-82721D01*
X523696Y-83304D01*
X524788Y-84471D01*
X525661Y-86221D01*
X525879Y-88262D01*
X525661Y-90013D01*
X524788Y-91763D01*
X523477Y-93221D01*
X521949Y-93804D01*
X520203Y-93221D01*
X518674Y-91471D01*
X517801Y-88846D01*
X517583Y-85929D01*
X518019Y-82138D01*
X518674Y-80095D01*
X519766Y-78054D01*
X521294Y-76596D01*
X522823Y-76304D01*
X524351Y-76887D01*
X525443Y-78346D01*
G01X534428Y-90304D02*
X535737Y-92346D01*
X537484Y-93512D01*
X539449Y-93804D01*
X541196Y-93512D01*
X542943Y-92054D01*
X544034Y-90304D01*
X544253Y-88554D01*
X543816Y-86513D01*
X542288Y-85054D01*
X540759Y-84471D01*
X538794D01*
G01X540759D02*
X542069Y-83596D01*
X543161Y-82138D01*
X543598Y-80388D01*
X543161Y-78637D01*
X542069Y-77179D01*
X540104Y-76304D01*
X538139Y-76596D01*
X536174Y-77763D01*
G01X559351Y-93804D02*
Y-76304D01*
X551272Y-88846D01*
X562190D01*
G01X570083Y-79221D02*
X571393Y-77471D01*
X572921Y-76596D01*
X574668Y-76304D01*
X576851Y-76887D01*
X578379Y-78346D01*
X578816Y-80095D01*
X578598Y-81846D01*
X577724Y-83304D01*
X573358Y-86221D01*
X571393Y-88262D01*
X570083Y-91180D01*
X569646Y-93804D01*
X578816D01*
G01X491114Y-48804D02*
Y-31304D01*
X496354D01*
X498101Y-32179D01*
X499411Y-34221D01*
X499848Y-36554D01*
X499411Y-38887D01*
X498319Y-40637D01*
X496354Y-41513D01*
X491114D01*
G01X517784Y-32763D02*
X516474Y-31887D01*
X514946Y-31304D01*
X513199D01*
X511234Y-32179D01*
X509706Y-33637D01*
X508614Y-35388D01*
X507741Y-38304D01*
X507522Y-40929D01*
X507959Y-43554D01*
X508614Y-45304D01*
X509924Y-47054D01*
X511453Y-48221D01*
X512981Y-48804D01*
X514509D01*
X516038Y-48221D01*
X517348Y-47346D01*
X518440Y-46180D01*
G01X532227Y-39471D02*
X533101Y-38596D01*
X533756Y-37138D01*
X534193Y-35095D01*
X533756Y-33346D01*
X532883Y-32179D01*
X531354Y-31304D01*
X525459D01*
Y-48804D01*
X532664D01*
X534193Y-47638D01*
X535066Y-45887D01*
X535503Y-43846D01*
X535066Y-41804D01*
X533756Y-40054D01*
X532227Y-39471D01*
X525459D01*
G01X541431Y-54637D02*
X554531D01*
G01X560459Y-48804D02*
Y-31304D01*
X570503Y-48804D01*
Y-31304D01*
G01X582981Y-48804D02*
X581234Y-48512D01*
X579706Y-47346D01*
X578396Y-45596D01*
X577522Y-43554D01*
X577086Y-41221D01*
Y-38887D01*
X577522Y-36554D01*
X578396Y-34512D01*
X579706Y-32763D01*
X581234Y-31596D01*
X582981Y-31304D01*
X584727Y-31596D01*
X586256Y-32763D01*
X587566Y-34512D01*
X588440Y-36554D01*
X588876Y-38887D01*
Y-41221D01*
X588440Y-43554D01*
X587566Y-45596D01*
X586256Y-47346D01*
X584727Y-48512D01*
X582981Y-48804D01*
G01X633822Y-31304D02*
X639281Y-48804D01*
X644740Y-31304D01*
G01X661148Y-48804D02*
X652414D01*
Y-31304D01*
X661148D01*
G01X657654Y-39762D02*
X652414D01*
G01X669914Y-48804D02*
Y-31304D01*
X675373D01*
X677119Y-32179D01*
X678211Y-33346D01*
X678648Y-35679D01*
X678211Y-38013D01*
X676901Y-39471D01*
X675373Y-40346D01*
X669914D01*
G01X675373D02*
X678648Y-48804D01*
G01X691781Y-49387D02*
X691344Y-49096D01*
Y-48512D01*
X691781Y-48221D01*
X692218Y-48512D01*
Y-49096D01*
X691781Y-49387D01*
G01X661383Y-79221D02*
X662693Y-77471D01*
X664221Y-76596D01*
X665968Y-76304D01*
X668151Y-76887D01*
X669679Y-78346D01*
X670116Y-80095D01*
X669898Y-81846D01*
X669024Y-83304D01*
X664658Y-86221D01*
X662693Y-88262D01*
X661383Y-91180D01*
X660946Y-93804D01*
X670116D01*
G01X831235Y-84471D02*
X830361Y-83596D01*
X829706Y-82138D01*
X829269Y-80095D01*
X829706Y-78346D01*
X830579Y-77179D01*
X832108Y-76304D01*
X838003D01*
Y-93804D01*
X830798D01*
X829269Y-92638D01*
X828396Y-90887D01*
X827959Y-88846D01*
X828396Y-86804D01*
X829706Y-85054D01*
X831235Y-84471D01*
X838003D01*
G01X820066Y-91471D02*
X818319Y-92929D01*
X816354Y-93804D01*
X814608D01*
X812861Y-92929D01*
X811551Y-91471D01*
X810896Y-89429D01*
X811333Y-87388D01*
X812424Y-85637D01*
X814389Y-84471D01*
X817009Y-83887D01*
X818538Y-82721D01*
X819193Y-80679D01*
X818756Y-78637D01*
X817664Y-77179D01*
X816136Y-76304D01*
X814608D01*
X813079Y-76887D01*
X811769Y-78346D01*
G01X803658Y-93804D02*
Y-76304D01*
X797981Y-90887D01*
X792304Y-76304D01*
Y-93804D01*
G01X785284D02*
Y-76304D01*
X780918D01*
X779171Y-77179D01*
X777861Y-78346D01*
X776769Y-80095D01*
X775896Y-82138D01*
X775678Y-85054D01*
X775896Y-87971D01*
X776769Y-90013D01*
X777861Y-91763D01*
X779171Y-92929D01*
X780918Y-93804D01*
X785284D01*
G01X767364Y-31304D02*
Y-48804D01*
X776098D01*
G01X793161D02*
Y-37138D01*
G01Y-39179D02*
X792288Y-38013D01*
X790977Y-37429D01*
X789449Y-37138D01*
X787921Y-37721D01*
X786611Y-38887D01*
X785737Y-40637D01*
X785301Y-42971D01*
X785737Y-45304D01*
X786611Y-47054D01*
X787921Y-48221D01*
X789449Y-48804D01*
X790977Y-48512D01*
X792288Y-47638D01*
X793161Y-46471D01*
G01X802146Y-54054D02*
X803456Y-54637D01*
X805203Y-54054D01*
X806294Y-52888D01*
X807168Y-51429D01*
X808477Y-46763D01*
X811316Y-37138D01*
G01X804329D02*
X808477Y-46763D01*
G01X820956Y-40929D02*
X827943D01*
X827288Y-38887D01*
X826196Y-37721D01*
X824668Y-37138D01*
X823139Y-37429D01*
X821829Y-38304D01*
X820956Y-40346D01*
X820519Y-42096D01*
Y-43846D01*
X820956Y-45596D01*
X822048Y-47346D01*
X823358Y-48512D01*
X824886Y-48804D01*
X826414Y-48221D01*
X827943Y-46471D01*
G01X838674Y-48804D02*
Y-37138D01*
G01Y-39471D02*
X839766Y-38304D01*
X840858Y-37429D01*
X842386Y-37138D01*
X843477Y-37429D01*
X844788Y-38304D01*
G01X931781Y-93804D02*
X930034Y-93512D01*
X928506Y-92346D01*
X927196Y-90596D01*
X926322Y-88554D01*
X925886Y-86221D01*
Y-83887D01*
X926322Y-81554D01*
X927196Y-79512D01*
X928506Y-77763D01*
X930034Y-76596D01*
X931781Y-76304D01*
X933527Y-76596D01*
X935056Y-77763D01*
X936366Y-79512D01*
X937240Y-81554D01*
X937676Y-83887D01*
Y-86221D01*
X937240Y-88554D01*
X936366Y-90596D01*
X935056Y-92346D01*
X933527Y-93512D01*
X931781Y-93804D01*
G01X933527Y-89137D02*
X936148Y-93804D01*
G01X944478Y-76304D02*
Y-88846D01*
X945351Y-91471D01*
X947098Y-93221D01*
X949281Y-93804D01*
X951464Y-93221D01*
X953211Y-91471D01*
X954084Y-88846D01*
Y-76304D01*
G01X964161D02*
X969401D01*
G01X966781D02*
Y-93804D01*
G01X964161D02*
X969401D01*
G01X979259D02*
Y-76304D01*
X989303Y-93804D01*
Y-76304D01*
G01X1006584Y-77763D02*
X1005274Y-76887D01*
X1003746Y-76304D01*
X1001999D01*
X1000034Y-77179D01*
X998506Y-78637D01*
X997414Y-80388D01*
X996541Y-83304D01*
X996322Y-85929D01*
X996759Y-88554D01*
X997414Y-90304D01*
X998724Y-92054D01*
X1000253Y-93221D01*
X1001781Y-93804D01*
X1003309D01*
X1004838Y-93221D01*
X1006148Y-92346D01*
X1007240Y-91180D01*
G01X1019281Y-93804D02*
Y-85929D01*
X1014914Y-76304D01*
G01X1023648D02*
X1019281Y-85929D01*
G01X909478Y-48804D02*
Y-31304D01*
X913844D01*
X915591Y-32179D01*
X916901Y-33346D01*
X917993Y-35095D01*
X918866Y-37138D01*
X919084Y-40054D01*
X918866Y-42971D01*
X917993Y-45013D01*
X916901Y-46763D01*
X915591Y-47929D01*
X913844Y-48804D01*
X909478D01*
G01X928506Y-40929D02*
X935493D01*
X934838Y-38887D01*
X933746Y-37721D01*
X932218Y-37138D01*
X930689Y-37429D01*
X929379Y-38304D01*
X928506Y-40346D01*
X928069Y-42096D01*
Y-43846D01*
X928506Y-45596D01*
X929598Y-47346D01*
X930908Y-48512D01*
X932436Y-48804D01*
X933964Y-48221D01*
X935493Y-46471D01*
G01X946006Y-46763D02*
X947098Y-47929D01*
X948626Y-48804D01*
X949936D01*
X951246Y-48221D01*
X952119Y-47346D01*
X952556Y-46180D01*
X952338Y-44429D01*
X951464Y-43554D01*
X947534Y-41804D01*
X946661Y-39762D01*
X947098Y-38304D01*
X947971Y-37429D01*
X949281Y-37138D01*
X950591Y-37429D01*
X951901Y-38304D01*
G01X966781Y-37138D02*
Y-48804D01*
G01Y-32471D02*
X966344Y-32179D01*
Y-31596D01*
X966781Y-31304D01*
X967218Y-31596D01*
Y-32179D01*
X966781Y-32471D01*
G01X981224Y-53179D02*
X982753Y-54346D01*
X984499Y-54637D01*
X986027Y-54346D01*
X987338Y-52888D01*
X988211Y-50846D01*
Y-37138D01*
G01Y-39471D02*
X987338Y-38304D01*
X986027Y-37429D01*
X984499Y-37138D01*
X982753Y-37721D01*
X981661Y-38887D01*
X980787Y-40929D01*
X980351Y-42971D01*
X980569Y-44721D01*
X981443Y-46763D01*
X982753Y-48221D01*
X984499Y-48804D01*
X985809Y-48512D01*
X987338Y-47346D01*
X988211Y-46180D01*
G01X998069Y-48804D02*
Y-37138D01*
G01Y-40054D02*
X998943Y-38596D01*
X1000253Y-37429D01*
X1001999Y-37138D01*
X1003527Y-37429D01*
X1004838Y-38596D01*
X1005493Y-40637D01*
Y-48804D01*
G01X1016006Y-40929D02*
X1022993D01*
X1022338Y-38887D01*
X1021246Y-37721D01*
X1019718Y-37138D01*
X1018189Y-37429D01*
X1016879Y-38304D01*
X1016006Y-40346D01*
X1015569Y-42096D01*
Y-43846D01*
X1016006Y-45596D01*
X1017098Y-47346D01*
X1018408Y-48512D01*
X1019936Y-48804D01*
X1021464Y-48221D01*
X1022993Y-46471D01*
G01X1033724Y-48804D02*
Y-37138D01*
G01Y-39471D02*
X1034816Y-38304D01*
X1035908Y-37429D01*
X1037436Y-37138D01*
X1038527Y-37429D01*
X1039838Y-38304D01*
G01X1080481Y-76304D02*
X1078734Y-76887D01*
X1077424Y-78346D01*
X1076551Y-80095D01*
X1075896Y-82429D01*
X1075678Y-85054D01*
X1075896Y-87679D01*
X1076551Y-90013D01*
X1077424Y-91763D01*
X1078734Y-93221D01*
X1080481Y-93804D01*
X1082227Y-93221D01*
X1083538Y-91763D01*
X1084411Y-90013D01*
X1085066Y-87679D01*
X1085284Y-85054D01*
X1085066Y-82429D01*
X1084411Y-80095D01*
X1083538Y-78346D01*
X1082227Y-76887D01*
X1080481Y-76304D01*
G01X1097981Y-93804D02*
X1099509Y-93512D01*
X1101256Y-92638D01*
X1102348Y-91180D01*
X1102784Y-89137D01*
X1102348Y-87096D01*
X1101038Y-85346D01*
X1099073Y-84471D01*
X1096889D01*
X1095579Y-83887D01*
X1094487Y-82429D01*
X1094051Y-80388D01*
X1094706Y-78346D01*
X1096234Y-76887D01*
X1097981Y-76304D01*
X1099727Y-76887D01*
X1101256Y-78346D01*
X1101911Y-80388D01*
X1101474Y-82429D01*
X1100383Y-83887D01*
X1099073Y-84471D01*
X1096889D01*
X1094924Y-85346D01*
X1093614Y-87096D01*
X1093178Y-89137D01*
X1093614Y-91180D01*
X1094706Y-92638D01*
X1096453Y-93512D01*
X1097981Y-93804D01*
G01X1111551Y-94387D02*
X1119411Y-76304D01*
G01X1132981D02*
X1131234Y-76887D01*
X1129924Y-78346D01*
X1129051Y-80095D01*
X1128396Y-82429D01*
X1128178Y-85054D01*
X1128396Y-87679D01*
X1129051Y-90013D01*
X1129924Y-91763D01*
X1131234Y-93221D01*
X1132981Y-93804D01*
X1134727Y-93221D01*
X1136038Y-91763D01*
X1136911Y-90013D01*
X1137566Y-87679D01*
X1137784Y-85054D01*
X1137566Y-82429D01*
X1136911Y-80095D01*
X1136038Y-78346D01*
X1134727Y-76887D01*
X1132981Y-76304D01*
G01X1150044Y-93804D02*
X1150481Y-90013D01*
X1151136Y-86804D01*
X1152009Y-83887D01*
X1153101Y-80679D01*
X1154848Y-76304D01*
X1146114D01*
G01X1164051Y-94387D02*
X1171911Y-76304D01*
G01X1181333Y-79221D02*
X1182643Y-77471D01*
X1184171Y-76596D01*
X1185918Y-76304D01*
X1188101Y-76887D01*
X1189629Y-78346D01*
X1190066Y-80095D01*
X1189848Y-81846D01*
X1188974Y-83304D01*
X1184608Y-86221D01*
X1182643Y-88262D01*
X1181333Y-91180D01*
X1180896Y-93804D01*
X1190066D01*
G01X1202981Y-76304D02*
X1201234Y-76887D01*
X1199924Y-78346D01*
X1199051Y-80095D01*
X1198396Y-82429D01*
X1198178Y-85054D01*
X1198396Y-87679D01*
X1199051Y-90013D01*
X1199924Y-91763D01*
X1201234Y-93221D01*
X1202981Y-93804D01*
X1204727Y-93221D01*
X1206038Y-91763D01*
X1206911Y-90013D01*
X1207566Y-87679D01*
X1207784Y-85054D01*
X1207566Y-82429D01*
X1206911Y-80095D01*
X1206038Y-78346D01*
X1204727Y-76887D01*
X1202981Y-76304D01*
G01X1220481Y-93804D02*
Y-76304D01*
X1217861Y-79804D01*
G01Y-93804D02*
X1223101D01*
G01X1237544D02*
X1237981Y-90013D01*
X1238636Y-86804D01*
X1239509Y-83887D01*
X1240601Y-80679D01*
X1242348Y-76304D01*
X1233614D01*
G01X1128178Y-48804D02*
Y-31304D01*
X1132544D01*
X1134291Y-32179D01*
X1135601Y-33346D01*
X1136693Y-35095D01*
X1137566Y-37138D01*
X1137784Y-40054D01*
X1137566Y-42971D01*
X1136693Y-45013D01*
X1135601Y-46763D01*
X1134291Y-47929D01*
X1132544Y-48804D01*
X1128178D01*
G01X1154411D02*
Y-37138D01*
G01Y-39179D02*
X1153538Y-38013D01*
X1152227Y-37429D01*
X1150699Y-37138D01*
X1149171Y-37721D01*
X1147861Y-38887D01*
X1146987Y-40637D01*
X1146551Y-42971D01*
X1146987Y-45304D01*
X1147861Y-47054D01*
X1149171Y-48221D01*
X1150699Y-48804D01*
X1152227Y-48512D01*
X1153538Y-47638D01*
X1154411Y-46471D01*
G01X1167981Y-31304D02*
Y-48804D01*
G01X1164924Y-37138D02*
X1171038D01*
G01X1182206Y-40929D02*
X1189193D01*
X1188538Y-38887D01*
X1187446Y-37721D01*
X1185918Y-37138D01*
X1184389Y-37429D01*
X1183079Y-38304D01*
X1182206Y-40346D01*
X1181769Y-42096D01*
Y-43846D01*
X1182206Y-45596D01*
X1183298Y-47346D01*
X1184608Y-48512D01*
X1186136Y-48804D01*
X1187664Y-48221D01*
X1189193Y-46471D01*
G01X3937Y0D02*
X116260D01*
G01X0Y3937D02*
G03X3937Y0I3937J0D01*
G01X0Y723480D02*
Y3937D01*
G01X416Y725241D02*
G03X0Y723480I3521J-1761D01*
G01X18597Y761603D02*
X416Y725241D01*
G01X22118Y763780D02*
G03X18597Y761603I1J-3937D01*
G01X386149Y763780D02*
X22118D01*
G01X120197Y3937D02*
Y429331D01*
G01X116260Y0D02*
G03X120197Y3937I0J3937D01*
G01X128071D02*
G03X132008Y0I3937J0D01*
G01X128071Y43308D02*
G03X120197I-3937J0D01*
G01X132008Y0D02*
X275709D01*
G01X128071Y3937D02*
Y43308D01*
G01X120197Y74016D02*
G03X128071I3937J0D01*
G01D02*
Y425394D01*
G01X124134Y433268D02*
X283583D01*
G01X124134D02*
G03X120197Y429331I0J-3937D01*
G01X188504Y425394D02*
X128071D01*
G01X152497Y21054D02*
G03I-4291J0D01*
G01X188504Y425394D02*
G03Y433268I0J3937D01*
G01X275709Y0D02*
G03X279646Y3937I0J3937D01*
G01X287520Y43308D02*
G03X279646I-3937J0D01*
G01Y3937D02*
Y43308D01*
G01Y74016D02*
G03X287520I3937J0D01*
G01X279646D02*
Y425394D01*
G01X265438Y405580D02*
G03I-4291J0D01*
G01X287520Y429331D02*
G03X283583Y433268I-3937J0D01*
G01X219213D02*
G03Y425394I0J-3937D01*
G01X279646D02*
X219213D01*
G01X291457Y0D02*
X921260D01*
G01X287520Y3937D02*
G03X291457Y0I3937J0D01*
G01X287520Y429331D02*
Y3937D01*
G01X408268Y188976D02*
Y723480D01*
G01Y188976D02*
G03X412205I1968J0D01*
G01X564173D02*
X412205D01*
G01X416142Y348379D02*
Y196851D01*
G01D02*
X560237D01*
G01X416142Y348379D02*
G03X408268I-3937J0D01*
G01Y379088D02*
G03X416142I3937J0D01*
G01Y688303D02*
Y379088D01*
G01Y688303D02*
G03X408268I-3937J0D01*
G01X389671Y761603D02*
G03X386149Y763780I-3522J-1760D01*
G01X407852Y725241D02*
X389671Y761603D01*
G01X408268Y723480D02*
G03X407852Y725241I-3937J0D01*
G01X524242Y763780D02*
X403757D01*
G01D02*
G03X400235Y758082I0J-3937D01*
G01X408268Y719012D02*
G03X416142I3937J0D01*
G01Y723480D02*
G03X414895Y728763I-11811J1D01*
G01X400235Y758082D02*
X414895Y728763D01*
G01X416142Y723480D02*
Y719012D01*
G01X490789Y356293D02*
G03I-4291J0D01*
G01X564173Y188976D02*
G03X568110I1968J0D01*
G01Y589622D02*
Y188976D01*
G01X560237Y261975D02*
Y196851D01*
G01X568111Y261975D02*
G03X560237I-3937J0D01*
G01Y292684D02*
G03X568111I3937J0D01*
G01X560237Y551040D02*
Y292684D01*
G01X568111Y551040D02*
G03X560237I-3937J0D01*
G01X568526Y591382D02*
G03X568110Y589622I3521J-1761D01*
G01X586707Y627745D02*
X568526Y591382D01*
G01X560237Y581748D02*
G03X568111I3937J0D01*
G01X561484Y594905D02*
G03X560237Y589622I10564J-5282D01*
G01D02*
Y581748D01*
G01X579665Y631267D02*
X561484Y594904D01*
G01X524242Y763780D02*
G03X532116I3937J0D01*
G01X834646D02*
X532116D01*
G01X590228Y629921D02*
G03X586707Y627745I0J-3937D01*
G01X842520Y629921D02*
X590228D01*
G01X590229Y637796D02*
G03X579665Y631268I0J-11812D01*
G01X590229Y637796D02*
X838583D01*
G01X842520Y629921D02*
G03X846457Y633858I0J3937D01*
G01Y759843D02*
Y633858D01*
G01X838583Y637796D02*
Y709449D01*
G01X850394Y763780D02*
G03X846457Y759843I0J-3937D01*
G01X903079Y763780D02*
X850394D01*
G01X812123Y734367D02*
G03I-4292J0D01*
G01X838583Y759843D02*
G03X834646Y763780I-3937J0D01*
G01X838583Y740158D02*
G03X846457I3937J0D01*
G01Y709449D02*
G03X838583I-3937J0D01*
G01Y740158D02*
Y759843D01*
G01X921260Y0D02*
G03X925197Y3937I0J3937D01*
G01D02*
Y723480D01*
G01X906600Y761603D02*
G03X903079Y763780I-3522J-1760D01*
G01X924781Y725241D02*
X906600Y761603D01*
G01X925197Y723480D02*
G03X924781Y725241I-3937J0D01*
G54D19*
X41868Y567316D03*
X49250Y580250D03*
X96900Y712200D03*
X189771Y559210D03*
X197030Y583440D03*
X870990Y222573D03*
G54D28*
X140550Y503660D03*
Y501100D03*
Y498540D03*
X134050D03*
Y503660D03*
X322850Y515460D03*
Y512900D03*
Y510340D03*
X316350D03*
Y515460D03*
X337502Y594713D03*
Y592153D03*
Y589593D03*
X331002D03*
Y594713D03*
X303250Y600760D03*
Y598200D03*
Y595640D03*
X296750D03*
Y600760D03*
X365230Y534960D03*
Y532400D03*
Y529840D03*
X358730D03*
Y534960D03*
X368250Y522660D03*
Y520100D03*
Y517540D03*
X361750D03*
Y522660D03*
G54D46*
X380500Y24500D03*
X369500D03*
X478429Y25800D03*
X467429D03*
G54D37*
X184800Y484556D03*
X171780Y496031D03*
X197400Y549000D03*
X170597Y539852D03*
X175200Y555000D03*
X184700Y552000D03*
X160157Y537164D03*
X149824Y542794D03*
X202380Y567970D03*
X169021Y610228D03*
X157800Y602900D03*
X154903Y608458D03*
X169242Y603107D03*
X163991Y606162D03*
X207820Y570860D03*
X206900Y577100D03*
X179500Y602800D03*
X186800Y595600D03*
X197264Y596849D03*
X224300Y552500D03*
X220500Y557800D03*
X221700Y545500D03*
X219700Y563100D03*
X236074Y536841D03*
X236260Y529177D03*
X257600Y543400D03*
X213201Y570843D03*
X219375Y581711D03*
X219638Y576359D03*
X219688Y587096D03*
X223292Y567000D03*
X219000Y617500D03*
X378965Y610613D03*
X361792Y625652D03*
G54D47*
X370950Y563500D03*
X363450Y559625D03*
Y567375D03*
X828266Y350214D03*
X820766Y346339D03*
Y354089D03*
G54D38*
X199890Y468960D03*
Y471520D03*
Y474080D03*
Y476640D03*
X183710D03*
Y474080D03*
Y471520D03*
Y468960D03*
X310092Y575349D03*
Y577909D03*
Y580469D03*
Y583029D03*
X297292D03*
Y580469D03*
Y577909D03*
Y575349D03*
X323039Y677049D03*
Y674489D03*
Y671929D03*
Y669369D03*
Y666809D03*
Y664249D03*
Y661689D03*
X345239D03*
Y664249D03*
Y666809D03*
Y669369D03*
Y671929D03*
Y674489D03*
Y677049D03*
G54D29*
X105474Y535824D03*
X91800Y677300D03*
X181148Y568251D03*
X192089Y582625D03*
X291811Y553256D03*
X866286Y159490D03*
X878598Y391533D03*
G54D48*
X367620Y603164D03*
Y599564D03*
X361800Y603500D03*
Y599900D03*
G54D39*
X178600Y483800D03*
G54D49*
X369480Y622436D03*
Y626036D03*
M02*
